# S9S_MB_2U (Grand Teton) — schematic netlist excerpt (pin names and nets, part order shuffled) for the footprints in the layout excerpt that follows; sources: Cadence DE-HDL packaged netlist, KiCad conversion of 03242023_DA0F0TMBIJ0_F0T_Motherboard_J_brd_V01_OCP.brd

R2593  Q_RES  100 1% CHIP  pkg 0402LF  page 296 : A = PVNN_TERM_CPU1 ; B = SVID_DIO1_CPU1_R
R1581  Q_RES  2K 1% CHIP  pkg 0402LF  page 183 : A = PU_SMB_PCH_PLD_3V3AUX_SCL ; B = P3V3_AUX

(kicad_pcb
	(version 20260206)
	(generator "pcbnew")
	(generator_version "10.0")
	(general
		(thickness 1.6)
		(legacy_teardrops no)
	)
	(paper "A4")
	(title_block
		(title "03242023_DA0F0TMBIJ0_F0T_Motherboard_J_brd_V01_OCP.brd")
		(comment 1 "Grand Teton / footprints 1077-1078 of 6105")
	)
	(layers
		(0 "F.Cu" signal "TOP")
		(4 "In1.Cu" signal "GND")
		(6 "In2.Cu" signal "IN1")
		(8 "In3.Cu" signal "GND1")
		(10 "In4.Cu" signal "IN2")
		(12 "In5.Cu" signal "GND2")
		(14 "In6.Cu" signal "IN3")
		(16 "In7.Cu" signal "GND3")
		(18 "In8.Cu" signal "VCC")
		(20 "In9.Cu" signal "VCC1")
		(22 "In10.Cu" signal "GND4")
		(24 "In11.Cu" signal "IN4")
		(26 "In12.Cu" signal "GND5")
		(28 "In13.Cu" signal "IN5")
		(30 "In14.Cu" signal "GND6")
		(32 "In15.Cu" signal "IN6")
		(34 "In16.Cu" signal "GND7")
		(2 "B.Cu" signal "BOTTOM")
		(9 "F.Adhes" user "F.Adhesive")
		(11 "B.Adhes" user "B.Adhesive")
		(13 "F.Paste" user "Package Geometry/Pastemask Top")
		(15 "B.Paste" user "Package Geometry/Pastemask Bottom")
		(5 "F.SilkS" user "Ref Des/Silkscreen Top")
		(7 "B.SilkS" user "Ref Des/Silkscreen Bottom")
		(1 "F.Mask" user "Board Geometry/Soldermask Top")
		(3 "B.Mask" user "Board Geometry/Soldermask Bottom")
		(17 "Dwgs.User" user "User.Drawings")
		(19 "Cmts.User" user "User.Comments")
		(21 "Eco1.User" user "User.Eco1")
		(23 "Eco2.User" user "User.Eco2")
		(25 "Edge.Cuts" user "Board Geometry/Outline")
		(27 "Margin" user)
		(31 "F.CrtYd" user "Package Geometry/Place Bound Top")
		(29 "B.CrtYd" user "Package Geometry/Place Bound Bottom")
		(35 "F.Fab" user "Ref Des/Assembly Top")
		(33 "B.Fab" user "Ref Des/Assembly Bottom")
	)
	(footprint ""
		(layer "F.Cu")
		(at 20.11426 -163.719256)
		(property "Reference" "R2593"
			(at 0 0 0)
			(layer "F.SilkS")
			(hide yes)
			(effects
				(font
					(size 1.27 1.27)
				)
			)
		)
		(property "Value" ""
			(at 0 0 0)
			(layer "F.Fab")
			(effects
				(font
					(size 1.27 1.27)
				)
			)
		)
		(duplicate_pad_numbers_are_jumpers no)
		(fp_line
			(start -0.7874 -0.4064)
			(end 0.7874 -0.4064)
			(stroke
				(width 0.1524)
				(type default)
			)
			(layer "F.SilkS")
		)
		(fp_line
			(start -0.7874 0.4064)
			(end -0.7874 -0.4064)
			(stroke
				(width 0.1524)
				(type default)
			)
			(layer "F.SilkS")
		)
		(fp_line
			(start 0.7874 -0.4064)
			(end 0.7874 0.4064)
			(stroke
				(width 0.1524)
				(type default)
			)
			(layer "F.SilkS")
		)
		(fp_line
			(start 0.7874 0.4064)
			(end -0.7874 0.4064)
			(stroke
				(width 0.1524)
				(type default)
			)
			(layer "F.SilkS")
		)
		(fp_line
			(start -0.67945 -0.305054)
			(end -0.12065 -0.305054)
			(stroke
				(width 0.1)
				(type default)
			)
			(layer "F.Fab")
		)
		(fp_line
			(start -0.67945 0.3048)
			(end -0.67945 -0.305054)
			(stroke
				(width 0.1)
				(type default)
			)
			(layer "F.Fab")
		)
		(fp_line
			(start -0.12065 -0.305054)
			(end -0.12065 -0.2794)
			(stroke
				(width 0.1)
				(type default)
			)
			(layer "F.Fab")
		)
		(fp_line
			(start -0.12065 -0.2794)
			(end 0.12065 -0.2794)
			(stroke
				(width 0.1)
				(type default)
			)
			(layer "F.Fab")
		)
		(fp_line
			(start -0.12065 0.2794)
			(end -0.12065 0.3048)
			(stroke
				(width 0.1)
				(type default)
			)
			(layer "F.Fab")
		)
		(fp_line
			(start -0.12065 0.3048)
			(end -0.67945 0.3048)
			(stroke
				(width 0.1)
				(type default)
			)
			(layer "F.Fab")
		)
		(fp_line
			(start 0.120396 0.2794)
			(end -0.12065 0.2794)
			(stroke
				(width 0.1)
				(type default)
			)
			(layer "F.Fab")
		)
		(fp_line
			(start 0.120396 0.3048)
			(end 0.120396 0.2794)
			(stroke
				(width 0.1)
				(type default)
			)
			(layer "F.Fab")
		)
		(fp_line
			(start 0.12065 -0.3048)
			(end 0.67945 -0.3048)
			(stroke
				(width 0.1)
				(type default)
			)
			(layer "F.Fab")
		)
		(fp_line
			(start 0.12065 -0.2794)
			(end 0.12065 -0.3048)
			(stroke
				(width 0.1)
				(type default)
			)
			(layer "F.Fab")
		)
		(fp_line
			(start 0.67945 -0.3048)
			(end 0.67945 0.3048)
			(stroke
				(width 0.1)
				(type default)
			)
			(layer "F.Fab")
		)
		(fp_line
			(start 0.67945 0.3048)
			(end 0.120396 0.3048)
			(stroke
				(width 0.1)
				(type default)
			)
			(layer "F.Fab")
		)
		(pad "1" smd circle
			(at -0.40005 0)
			(size 0 0)
			(layers "F.Cu" "F.Mask" "F.Paste")
			(net "PVNN_TERM_CPU1")
		)
		(pad "2" smd circle
			(at 0.40005 0)
			(size 0 0)
			(layers "F.Cu" "F.Mask" "F.Paste")
			(net "SVID_DIO1_CPU1_R")
		)
	)
	(footprint ""
		(layer "F.Cu")
		(at 312.443622 -41.519348 180)
		(property "Reference" "R1581"
			(at 0 0 180)
			(layer "F.SilkS")
			(hide yes)
			(effects
				(font
					(size 1.27 1.27)
				)
			)
		)
		(property "Value" ""
			(at 0 0 180)
			(layer "F.Fab")
			(effects
				(font
					(size 1.27 1.27)
				)
			)
		)
		(duplicate_pad_numbers_are_jumpers no)
		(fp_line
			(start 0.7874 0.4064)
			(end -0.7874 0.4064)
			(stroke
				(width 0.1524)
				(type default)
			)
			(layer "F.SilkS")
		)
		(fp_line
			(start 0.7874 -0.4064)
			(end 0.7874 0.4064)
			(stroke
				(width 0.1524)
				(type default)
			)
			(layer "F.SilkS")
		)
		(fp_line
			(start -0.7874 0.4064)
			(end -0.7874 -0.4064)
			(stroke
				(width 0.1524)
				(type default)
			)
			(layer "F.SilkS")
		)
		(fp_line
			(start -0.7874 -0.4064)
			(end 0.7874 -0.4064)
			(stroke
				(width 0.1524)
				(type default)
			)
			(layer "F.SilkS")
		)
		(fp_line
			(start 0.67945 0.3048)
			(end 0.120396 0.3048)
			(stroke
				(width 0.1)
				(type default)
			)
			(layer "F.Fab")
		)
		(fp_line
			(start 0.67945 -0.3048)
			(end 0.67945 0.3048)
			(stroke
				(width 0.1)
				(type default)
			)
			(layer "F.Fab")
		)
		(fp_line
			(start 0.12065 -0.2794)
			(end 0.12065 -0.3048)
			(stroke
				(width 0.1)
				(type default)
			)
			(layer "F.Fab")
		)
		(fp_line
			(start 0.12065 -0.3048)
			(end 0.67945 -0.3048)
			(stroke
				(width 0.1)
				(type default)
			)
			(layer "F.Fab")
		)
		(fp_line
			(start 0.120396 0.3048)
			(end 0.120396 0.2794)
			(stroke
				(width 0.1)
				(type default)
			)
			(layer "F.Fab")
		)
		(fp_line
			(start 0.120396 0.2794)
			(end -0.12065 0.2794)
			(stroke
				(width 0.1)
				(type default)
			)
			(layer "F.Fab")
		)
		(fp_line
			(start -0.12065 0.3048)
			(end -0.67945 0.3048)
			(stroke
				(width 0.1)
				(type default)
			)
			(layer "F.Fab")
		)
		(fp_line
			(start -0.12065 0.2794)
			(end -0.12065 0.3048)
			(stroke
				(width 0.1)
				(type default)
			)
			(layer "F.Fab")
		)
		(fp_line
			(start -0.12065 -0.2794)
			(end 0.12065 -0.2794)
			(stroke
				(width 0.1)
				(type default)
			)
			(layer "F.Fab")
		)
		(fp_line
			(start -0.12065 -0.305054)
			(end -0.12065 -0.2794)
			(stroke
				(width 0.1)
				(type default)
			)
			(layer "F.Fab")
		)
		(fp_line
			(start -0.67945 0.3048)
			(end -0.67945 -0.305054)
			(stroke
				(width 0.1)
				(type default)
			)
			(layer "F.Fab")
		)
		(fp_line
			(start -0.67945 -0.305054)
			(end -0.12065 -0.305054)
			(stroke
				(width 0.1)
				(type default)
			)
			(layer "F.Fab")
		)
		(pad "1" smd circle
			(at -0.40005 0 180)
			(size 0 0)
			(layers "F.Cu" "F.Mask" "F.Paste")
			(net "PU_SMB_PCH_PLD_3V3AUX_SCL")
		)
		(pad "2" smd circle
			(at 0.40005 0 180)
			(size 0 0)
			(layers "F.Cu" "F.Mask" "F.Paste")
			(net "P3V3_AUX")
		)
	)
)
